# T6G (Grand Teton) — schematic netlist excerpt (pin names and nets, part order shuffled) for the footprints in the layout excerpt that follows; sources: Cadence DE-HDL packaged netlist, KiCad conversion of 04192023_DAF0TMB3IC0_F0TG_MB_C_brd_V02_OCP.brd

DB13  TDR_3P  EMPTY  pkg TH2  page 260
  GND  = T1_GND
  IO1  = TDR_SE_45_OHM_IN5
  IO2  = TDR_SE_45_OHM_IN5

R106  Q_RES  1K 1% EMPTY  pkg 0402LF  page 101 : A = P3V3 ; B = PWRGD_CHD_CPU1_DIMM
L17  Q_INDUCTOR  FCM2012KF-601T/0.5A IND  pkg SMLF  page 233 : \1\ = P3V3_AUX ; \2\ = VFG3P3_CLK_GEN

(kicad_pcb
	(version 20260206)
	(generator "pcbnew")
	(generator_version "10.0")
	(general
		(thickness 1.6)
		(legacy_teardrops no)
	)
	(paper "A4")
	(title_block
		(title "04192023_DAF0TMB3IC0_F0TG_MB_C_brd_V02_OCP.brd")
		(comment 1 "Grand Teton / footprints 7844-7846 of 8354")
	)
	(layers
		(0 "F.Cu" signal "TOP")
		(4 "In1.Cu" signal "GND")
		(6 "In2.Cu" signal "IN1")
		(8 "In3.Cu" signal "GND1")
		(10 "In4.Cu" signal "IN2")
		(12 "In5.Cu" signal "GND2")
		(14 "In6.Cu" signal "IN3")
		(16 "In7.Cu" signal "GND3")
		(18 "In8.Cu" signal "VCC")
		(20 "In9.Cu" signal "VCC1")
		(22 "In10.Cu" signal "GND4")
		(24 "In11.Cu" signal "IN4")
		(26 "In12.Cu" signal "GND5")
		(28 "In13.Cu" signal "IN5")
		(30 "In14.Cu" signal "GND6")
		(32 "In15.Cu" signal "IN6")
		(34 "In16.Cu" signal "GND7")
		(2 "B.Cu" signal "BOTTOM")
		(9 "F.Adhes" user "F.Adhesive")
		(11 "B.Adhes" user "B.Adhesive")
		(13 "F.Paste" user "Package Geometry/Pastemask Top")
		(15 "B.Paste" user "Package Geometry/Pastemask Bottom")
		(5 "F.SilkS" user "Ref Des/Silkscreen Top")
		(7 "B.SilkS" user "Ref Des/Silkscreen Bottom")
		(1 "F.Mask" user "Board Geometry/Soldermask Top")
		(3 "B.Mask" user "Board Geometry/Soldermask Bottom")
		(17 "Dwgs.User" user "User.Drawings")
		(19 "Cmts.User" user "User.Comments")
		(21 "Eco1.User" user "User.Eco1")
		(23 "Eco2.User" user "User.Eco2")
		(25 "Edge.Cuts" user "Board Geometry/Outline")
		(27 "Margin" user)
		(31 "F.CrtYd" user "Package Geometry/Place Bound Top")
		(29 "B.CrtYd" user "Package Geometry/Place Bound Bottom")
		(35 "F.Fab" user "Ref Des/Assembly Top")
		(33 "B.Fab" user "Ref Des/Assembly Bottom")
	)
	(footprint ""
		(layer "B.Cu")
		(at 33.467294 -193.996564)
		(property "Reference" "R106"
			(at 0 0 0)
			(layer "B.SilkS")
			(hide yes)
			(effects
				(font
					(size 1.27 1.27)
				)
				(justify mirror)
			)
		)
		(property "Value" ""
			(at 0 0 0)
			(layer "B.Fab")
			(effects
				(font
					(size 1.27 1.27)
				)
				(justify mirror)
			)
		)
		(duplicate_pad_numbers_are_jumpers no)
		(fp_line
			(start -0.7874 -0.4064)
			(end -0.7874 0.4064)
			(stroke
				(width 0.1524)
				(type default)
			)
			(layer "B.SilkS")
		)
		(fp_line
			(start -0.7874 0.4064)
			(end 0.7874 0.4064)
			(stroke
				(width 0.1524)
				(type default)
			)
			(layer "B.SilkS")
		)
		(fp_line
			(start 0.7874 -0.4064)
			(end -0.7874 -0.4064)
			(stroke
				(width 0.1524)
				(type default)
			)
			(layer "B.SilkS")
		)
		(fp_line
			(start 0.7874 0.4064)
			(end 0.7874 -0.4064)
			(stroke
				(width 0.1524)
				(type default)
			)
			(layer "B.SilkS")
		)
		(fp_line
			(start -0.67945 -0.3048)
			(end -0.67945 0.3048)
			(stroke
				(width 0.1)
				(type default)
			)
			(layer "B.Fab")
		)
		(fp_line
			(start -0.67945 0.3048)
			(end -0.120396 0.3048)
			(stroke
				(width 0.1)
				(type default)
			)
			(layer "B.Fab")
		)
		(fp_line
			(start -0.12065 -0.3048)
			(end -0.67945 -0.3048)
			(stroke
				(width 0.1)
				(type default)
			)
			(layer "B.Fab")
		)
		(fp_line
			(start -0.12065 -0.2794)
			(end -0.12065 -0.3048)
			(stroke
				(width 0.1)
				(type default)
			)
			(layer "B.Fab")
		)
		(fp_line
			(start -0.120396 0.2794)
			(end 0.12065 0.2794)
			(stroke
				(width 0.1)
				(type default)
			)
			(layer "B.Fab")
		)
		(fp_line
			(start -0.120396 0.3048)
			(end -0.120396 0.2794)
			(stroke
				(width 0.1)
				(type default)
			)
			(layer "B.Fab")
		)
		(fp_line
			(start 0.12065 -0.305054)
			(end 0.12065 -0.2794)
			(stroke
				(width 0.1)
				(type default)
			)
			(layer "B.Fab")
		)
		(fp_line
			(start 0.12065 -0.2794)
			(end -0.12065 -0.2794)
			(stroke
				(width 0.1)
				(type default)
			)
			(layer "B.Fab")
		)
		(fp_line
			(start 0.12065 0.2794)
			(end 0.12065 0.3048)
			(stroke
				(width 0.1)
				(type default)
			)
			(layer "B.Fab")
		)
		(fp_line
			(start 0.12065 0.3048)
			(end 0.67945 0.3048)
			(stroke
				(width 0.1)
				(type default)
			)
			(layer "B.Fab")
		)
		(fp_line
			(start 0.67945 -0.305054)
			(end 0.12065 -0.305054)
			(stroke
				(width 0.1)
				(type default)
			)
			(layer "B.Fab")
		)
		(fp_line
			(start 0.67945 0.3048)
			(end 0.67945 -0.305054)
			(stroke
				(width 0.1)
				(type default)
			)
			(layer "B.Fab")
		)
		(pad "1" smd circle
			(at 0.40005 0 180)
			(size 0 0)
			(layers "B.Cu" "B.Mask" "B.Paste")
			(net "P3V3")
		)
		(pad "2" smd circle
			(at -0.40005 0 180)
			(size 0 0)
			(layers "B.Cu" "B.Mask" "B.Paste")
			(net "PWRGD_CHD_CPU1_DIMM")
		)
	)
	(footprint ""
		(layer "B.Cu")
		(at 10.808208 -138.93927 180)
		(property "Reference" "L17"
			(at 0 0 0)
			(layer "B.SilkS")
			(hide yes)
			(effects
				(font
					(size 1.27 1.27)
				)
				(justify mirror)
			)
		)
		(property "Value" ""
			(at 0 0 0)
			(layer "B.Fab")
			(effects
				(font
					(size 1.27 1.27)
				)
				(justify mirror)
			)
		)
		(duplicate_pad_numbers_are_jumpers no)
		(fp_line
			(start 1.63576 -0.8128)
			(end 1.63576 0.8128)
			(stroke
				(width 0.1524)
				(type default)
			)
			(layer "B.SilkS")
		)
		(fp_line
			(start 1.63576 -0.8128)
			(end -1.63576 -0.8128)
			(stroke
				(width 0.1524)
				(type default)
			)
			(layer "B.SilkS")
		)
		(fp_line
			(start -1.63576 0.8128)
			(end 1.63576 0.8128)
			(stroke
				(width 0.1524)
				(type default)
			)
			(layer "B.SilkS")
		)
		(fp_line
			(start -1.63576 -0.8128)
			(end -1.63576 0.8128)
			(stroke
				(width 0.1524)
				(type default)
			)
			(layer "B.SilkS")
		)
		(fp_line
			(start 1.56083 0.7366)
			(end 1.524 0.7366)
			(stroke
				(width 0.1)
				(type default)
			)
			(layer "B.Fab")
		)
		(fp_line
			(start 1.56083 -0.738632)
			(end 1.56083 0.7366)
			(stroke
				(width 0.1)
				(type default)
			)
			(layer "B.Fab")
		)
		(fp_line
			(start 1.524 0.7366)
			(end -1.524 0.7366)
			(stroke
				(width 0.1)
				(type default)
			)
			(layer "B.Fab")
		)
		(fp_line
			(start -1.524 0.7366)
			(end -1.560576 0.7366)
			(stroke
				(width 0.1)
				(type default)
			)
			(layer "B.Fab")
		)
		(fp_line
			(start -1.560576 0.7366)
			(end -1.560576 -0.738632)
			(stroke
				(width 0.1)
				(type default)
			)
			(layer "B.Fab")
		)
		(fp_line
			(start -1.560576 -0.738632)
			(end 1.56083 -0.738632)
			(stroke
				(width 0.1)
				(type default)
			)
			(layer "B.Fab")
		)
		(pad "1" smd rect
			(at 0.94996 0 180)
			(size 1.1176 1.3716)
			(layers "B.Cu" "B.Mask" "B.Paste")
			(net "P3V3_AUX")
		)
		(pad "2" smd rect
			(at -0.94996 0 180)
			(size 1.1176 1.3716)
			(layers "B.Cu" "B.Mask" "B.Paste")
			(net "VFG3P3_CLK_GEN")
		)
	)
	(footprint ""
		(layer "B.Cu")
		(at 473.874592 -202.415902 180)
		(property "Reference" "DB13"
			(at 2.443988 -8.440928 270)
			(unlocked yes)
			(layer "B.SilkS")
			(effects
				(font
					(size 0.7874 0.5842)
					(thickness 0.1524)
				)
				(justify left mirror)
			)
		)
		(property "Value" ""
			(at 0 0 0)
			(layer "B.Fab")
			(effects
				(font
					(size 1.27 1.27)
				)
				(justify mirror)
			)
		)
		(duplicate_pad_numbers_are_jumpers no)
		(fp_line
			(start 3.330702 -4.771136)
			(end -3.330702 -4.771136)
			(stroke
				(width 0.1524)
				(type default)
			)
			(layer "B.SilkS")
		)
		(fp_line
			(start 0 4.011168)
			(end 3.330702 -4.771136)
			(stroke
				(width 0.1524)
				(type default)
			)
			(layer "B.SilkS")
		)
		(fp_line
			(start -3.330702 -4.771136)
			(end 0 4.011168)
			(stroke
				(width 0.1524)
				(type default)
			)
			(layer "B.SilkS")
		)
		(fp_line
			(start 3.330702 -4.771136)
			(end -3.330702 -4.771136)
			(stroke
				(width 0.1)
				(type default)
			)
			(layer "B.Fab")
		)
		(fp_line
			(start 0 4.011168)
			(end 3.330702 -4.771136)
			(stroke
				(width 0.1)
				(type default)
			)
			(layer "B.Fab")
		)
		(fp_line
			(start -3.330702 -4.771136)
			(end 0 4.011168)
			(stroke
				(width 0.1)
				(type default)
			)
			(layer "B.Fab")
		)
		(pad "1" thru_hole circle
			(at 0 0)
			(size 2.159 2.159)
			(drill 1.7018)
			(layers "*.Cu" "*.Mask")
			(remove_unused_layers no)
			(net "T1_GND")
			(clearance 0.0254)
			(thermal_gap 0.0254)
		)
		(pad "2" thru_hole circle
			(at 1.27 -3.348736)
			(size 2.159 2.159)
			(drill 1.7018)
			(layers "*.Cu" "*.Mask")
			(remove_unused_layers no)
			(net "TDR_SE_45_OHM_IN5")
			(clearance 0.0254)
			(thermal_gap 0.0254)
		)
		(pad "3" thru_hole circle
			(at -1.27 -3.348736)
			(size 2.159 2.159)
			(drill 1.7018)
			(layers "*.Cu" "*.Mask")
			(remove_unused_layers no)
			(net "TDR_SE_45_OHM_IN5")
			(clearance 0.0254)
			(thermal_gap 0.0254)
		)
	)
)
